(kicad_pcb
	(version 20260206)
	(generator "pcbnew")
	(generator_version "10.0")
	(general
		(thickness 1.6)
		(legacy_teardrops no)
	)
	(paper "A4")
	(title_block
		(title "peb — Lightning_PEB_BRD.brd")
		(comment 1 "Lightning (Wiwynn / Facebook NVMe JBOF) / footprints 477-483 of 2563")
	)
	(layers
		(0 "F.Cu" signal "TOP")
		(4 "In1.Cu" signal "L2GND")
		(6 "In2.Cu" signal "L3")
		(8 "In3.Cu" signal "L4VCC")
		(10 "In4.Cu" signal "L5VCC")
		(12 "In5.Cu" signal "L6")
		(14 "In6.Cu" signal "L7GND")
		(2 "B.Cu" signal "BOTTOM")
		(9 "F.Adhes" user "F.Adhesive")
		(11 "B.Adhes" user "B.Adhesive")
		(13 "F.Paste" user "Package Geometry/Pastemask Top")
		(15 "B.Paste" user "Package Geometry/Pastemask Bottom")
		(5 "F.SilkS" user "Ref Des/Silkscreen Top")
		(7 "B.SilkS" user "Ref Des/Silkscreen Bottom")
		(1 "F.Mask" user "Board Geometry/Soldermask Top")
		(3 "B.Mask" user "Board Geometry/Soldermask Bottom")
		(17 "Dwgs.User" user "User.Drawings")
		(19 "Cmts.User" user "User.Comments")
		(21 "Eco1.User" user "User.Eco1")
		(23 "Eco2.User" user "User.Eco2")
		(25 "Edge.Cuts" user "Board Geometry/Outline")
		(27 "Margin" user)
		(31 "F.CrtYd" user "Package Geometry/Place Bound Top")
		(29 "B.CrtYd" user "Package Geometry/Place Bound Bottom")
		(35 "F.Fab" user "Ref Des/Assembly Top")
		(33 "B.Fab" user "Ref Des/Assembly Bottom")
	)
	(footprint ""
		(layer "F.Cu")
		(at 35.247326 -146.48688 180)
		(property "Reference" "R248"
			(at 0 0 180)
			(layer "F.SilkS")
			(hide yes)
			(effects
				(font
					(size 1.27 1.27)
				)
			)
		)
		(property "Value" "240R2F-1-GP"
			(at 0.064008 -3.993896 180)
			(unlocked yes)
			(layer "F.Fab")
			(hide yes)
			(effects
				(font
					(size 1.016 1.016)
					(thickness 0.1524)
				)
			)
		)
		(property "Device Type" "R402H16"
			(at 0.064008 -5.517896 180)
			(unlocked yes)
			(layer "F.Fab")
			(hide yes)
			(effects
				(font
					(size 1.016 1.016)
					(thickness 0.1524)
				)
			)
		)
		(duplicate_pad_numbers_are_jumpers no)
		(fp_line
			(start 0.508 -0.9398)
			(end -0.508 -0.9398)
			(stroke
				(width 0.1524)
				(type default)
			)
			(layer "F.SilkS")
		)
		(fp_line
			(start -0.508 -0.9398)
			(end -0.508 0.9398)
			(stroke
				(width 0.1524)
				(type default)
			)
			(layer "F.SilkS")
		)
		(fp_rect
			(start -0.508 0.9398)
			(end 0.508 -0.9398)
			(stroke
				(width 0)
				(type default)
			)
			(fill no)
			(layer "F.CrtYd")
		)
		(fp_rect
			(start -0.508 0.9398)
			(end 0.508 -0.9398)
			(stroke
				(width 0)
				(type default)
			)
			(fill no)
			(layer "F.Fab")
		)
		(pad "1" smd custom
			(at 0 -0.4445 180)
			(size 0.1397 0.1397)
			(layers "F.Cu" "F.Mask" "F.Paste")
			(net "GND")
			(options
				(clearance outline)
				(anchor circle)
			)
			(primitives
				(gr_poly
					(pts
						(arc
							(start -0.1778 -0.2794)
							(mid -0.249642 -0.249642)
							(end -0.2794 -0.1778)
						)
						(arc
							(start -0.2794 0.1778)
							(mid -0.249642 0.249642)
							(end -0.1778 0.2794)
						)
						(arc
							(start 0.1778 0.2794)
							(mid 0.249642 0.249642)
							(end 0.2794 0.1778)
						)
						(arc
							(start 0.2794 -0.1778)
							(mid 0.249642 -0.249642)
							(end 0.1778 -0.2794)
						)
					)
					(width 0)
					(fill yes)
				)
			)
		)
		(pad "2" smd custom
			(at 0 0.4445 180)
			(size 0.1397 0.1397)
			(layers "F.Cu" "F.Mask" "F.Paste")
			(net "PD_ZQ")
			(options
				(clearance outline)
				(anchor circle)
			)
			(primitives
				(gr_poly
					(pts
						(arc
							(start -0.1778 -0.2794)
							(mid -0.249642 -0.249642)
							(end -0.2794 -0.1778)
						)
						(arc
							(start -0.2794 0.1778)
							(mid -0.249642 0.249642)
							(end -0.1778 0.2794)
						)
						(arc
							(start 0.1778 0.2794)
							(mid 0.249642 0.249642)
							(end 0.2794 0.1778)
						)
						(arc
							(start 0.2794 -0.1778)
							(mid 0.249642 -0.249642)
							(end 0.1778 -0.2794)
						)
					)
					(width 0)
					(fill yes)
				)
			)
		)
	)
	(footprint ""
		(layer "F.Cu")
		(at 23.876 -136.779 90)
		(property "Reference" "R366"
			(at 0 0 90)
			(layer "F.SilkS")
			(hide yes)
			(effects
				(font
					(size 1.27 1.27)
				)
			)
		)
		(property "Value" "3K3R2F-2-GP"
			(at 0.064008 -3.993896 90)
			(unlocked yes)
			(layer "F.Fab")
			(hide yes)
			(effects
				(font
					(size 1.016 1.016)
					(thickness 0.1524)
				)
			)
		)
		(property "Device Type" "R402H16"
			(at 0.064008 -5.517896 90)
			(unlocked yes)
			(layer "F.Fab")
			(hide yes)
			(effects
				(font
					(size 1.016 1.016)
					(thickness 0.1524)
				)
			)
		)
		(duplicate_pad_numbers_are_jumpers no)
		(fp_line
			(start 0.508 -0.9398)
			(end -0.508 -0.9398)
			(stroke
				(width 0.1524)
				(type default)
			)
			(layer "F.SilkS")
		)
		(fp_line
			(start -0.508 -0.9398)
			(end -0.508 0.9398)
			(stroke
				(width 0.1524)
				(type default)
			)
			(layer "F.SilkS")
		)
		(fp_rect
			(start -0.508 0.9398)
			(end 0.508 -0.9398)
			(stroke
				(width 0)
				(type default)
			)
			(fill no)
			(layer "F.CrtYd")
		)
		(fp_rect
			(start -0.508 0.9398)
			(end 0.508 -0.9398)
			(stroke
				(width 0)
				(type default)
			)
			(fill no)
			(layer "F.Fab")
		)
		(pad "1" smd custom
			(at 0 -0.4445 90)
			(size 0.1397 0.1397)
			(layers "F.Cu" "F.Mask" "F.Paste")
			(net "P3V3_STBY")
			(options
				(clearance outline)
				(anchor circle)
			)
			(primitives
				(gr_poly
					(pts
						(arc
							(start -0.1778 -0.2794)
							(mid -0.249642 -0.249642)
							(end -0.2794 -0.1778)
						)
						(arc
							(start -0.2794 0.1778)
							(mid -0.249642 0.249642)
							(end -0.1778 0.2794)
						)
						(arc
							(start 0.1778 0.2794)
							(mid 0.249642 0.249642)
							(end 0.2794 0.1778)
						)
						(arc
							(start 0.2794 -0.1778)
							(mid 0.249642 -0.249642)
							(end 0.1778 -0.2794)
						)
					)
					(width 0)
					(fill yes)
				)
			)
		)
		(pad "2" smd custom
			(at 0 0.4445 90)
			(size 0.1397 0.1397)
			(layers "F.Cu" "F.Mask" "F.Paste")
			(net "ROMD6")
			(options
				(clearance outline)
				(anchor circle)
			)
			(primitives
				(gr_poly
					(pts
						(arc
							(start -0.1778 -0.2794)
							(mid -0.249642 -0.249642)
							(end -0.2794 -0.1778)
						)
						(arc
							(start -0.2794 0.1778)
							(mid -0.249642 0.249642)
							(end -0.1778 0.2794)
						)
						(arc
							(start 0.1778 0.2794)
							(mid 0.249642 0.249642)
							(end 0.2794 0.1778)
						)
						(arc
							(start 0.2794 -0.1778)
							(mid 0.249642 -0.249642)
							(end 0.1778 -0.2794)
						)
					)
					(width 0)
					(fill yes)
				)
			)
		)
	)
	(footprint ""
		(layer "F.Cu")
		(at 267.4366 -8.2296)
		(property "Reference" "U79"
			(at 0 0 0)
			(layer "F.SilkS")
			(hide yes)
			(effects
				(font
					(size 1.27 1.27)
				)
			)
		)
		(property "Value" "ADM6315-29D2ARTZ-GP"
			(at -0.0127 -12.8016 0)
			(unlocked yes)
			(layer "F.Fab")
			(hide yes)
			(effects
				(font
					(size 1.016 1.016)
					(thickness 0.1524)
				)
			)
		)
		(property "Device Type" "SOT-143-6H49"
			(at -0.0635 -14.6812 0)
			(unlocked yes)
			(layer "F.Fab")
			(hide yes)
			(effects
				(font
					(size 1.016 1.016)
					(thickness 0.1524)
				)
			)
		)
		(duplicate_pad_numbers_are_jumpers no)
		(fp_line
			(start -1.7907 1.8669)
			(end -1.7907 0.3937)
			(stroke
				(width 0.3302)
				(type default)
			)
			(layer "F.SilkS")
		)
		(fp_line
			(start -1.6891 -1.778)
			(end 1.6891 -1.778)
			(stroke
				(width 0.1524)
				(type default)
			)
			(layer "F.SilkS")
		)
		(fp_line
			(start -1.6891 1.778)
			(end -1.6891 -1.778)
			(stroke
				(width 0.1524)
				(type default)
			)
			(layer "F.SilkS")
		)
		(fp_line
			(start -0.3175 1.8669)
			(end -1.7907 1.8669)
			(stroke
				(width 0.3302)
				(type default)
			)
			(layer "F.SilkS")
		)
		(fp_line
			(start 1.6891 -1.778)
			(end 1.6891 1.778)
			(stroke
				(width 0.1524)
				(type default)
			)
			(layer "F.SilkS")
		)
		(fp_line
			(start 1.6891 1.778)
			(end -1.6891 1.778)
			(stroke
				(width 0.1524)
				(type default)
			)
			(layer "F.SilkS")
		)
		(fp_poly
			(pts
				(xy -0.7239 1.8542) (xy -1.3335 2.4638) (xy -0.1143 2.4638)
			)
			(stroke
				(width 0)
				(type default)
			)
			(fill yes)
			(layer "F.SilkS")
		)
		(fp_rect
			(start -1.9431 2.032)
			(end 1.9431 -2.032)
			(stroke
				(width 0)
				(type default)
			)
			(fill no)
			(layer "F.CrtYd")
		)
		(fp_poly
			(pts
				(xy 1.9431 2.032) (xy 1.9431 -2.032) (xy -1.9431 -2.032) (xy -1.9431 2.032)
			)
			(stroke
				(width 0)
				(type default)
			)
			(fill no)
			(layer "F.Fab")
		)
		(pad "1" smd rect
			(at -0.75311 0.9652)
			(size 1.1176 1.1176)
			(layers "F.Cu" "F.Mask" "F.Paste")
			(net "GND")
		)
		(pad "2" smd rect
			(at 0.9525 0.9652)
			(size 0.7112 1.1176)
			(layers "F.Cu" "F.Mask" "F.Paste")
			(net "ADM6315_PM8536_RST#")
		)
		(pad "3" smd rect
			(at 0.9525 -0.9652)
			(size 0.7112 1.1176)
			(layers "F.Cu" "F.Mask" "F.Paste")
			(net "PM8536_RST#_LS_R")
		)
		(pad "4" smd rect
			(at -0.9525 -0.9652)
			(size 0.7112 1.1176)
			(layers "F.Cu" "F.Mask" "F.Paste")
			(net "P3V3_STBY")
		)
	)
	(footprint ""
		(layer "F.Cu")
		(at 186.629802 -8.098028 -90)
		(property "Reference" "R532"
			(at 0 0 270)
			(layer "F.SilkS")
			(hide yes)
			(effects
				(font
					(size 1.27 1.27)
				)
			)
		)
		(property "Value" "1KR2F-3-GP"
			(at 0.064008 -3.993896 270)
			(unlocked yes)
			(layer "F.Fab")
			(hide yes)
			(effects
				(font
					(size 1.016 1.016)
					(thickness 0.1524)
				)
			)
		)
		(property "Device Type" "R402H16"
			(at 0.064008 -5.517896 270)
			(unlocked yes)
			(layer "F.Fab")
			(hide yes)
			(effects
				(font
					(size 1.016 1.016)
					(thickness 0.1524)
				)
			)
		)
		(duplicate_pad_numbers_are_jumpers no)
		(fp_line
			(start -0.508 -0.9398)
			(end -0.508 0.9398)
			(stroke
				(width 0.1524)
				(type default)
			)
			(layer "F.SilkS")
		)
		(fp_line
			(start 0.508 -0.9398)
			(end -0.508 -0.9398)
			(stroke
				(width 0.1524)
				(type default)
			)
			(layer "F.SilkS")
		)
		(fp_rect
			(start -0.508 0.9398)
			(end 0.508 -0.9398)
			(stroke
				(width 0)
				(type default)
			)
			(fill no)
			(layer "F.CrtYd")
		)
		(fp_rect
			(start -0.508 0.9398)
			(end 0.508 -0.9398)
			(stroke
				(width 0)
				(type default)
			)
			(fill no)
			(layer "F.Fab")
		)
		(pad "1" smd custom
			(at 0 -0.4445 270)
			(size 0.1397 0.1397)
			(layers "F.Cu" "F.Mask" "F.Paste")
			(net "ENCLO_LED_BLUE_OUT")
			(options
				(clearance outline)
				(anchor circle)
			)
			(primitives
				(gr_poly
					(pts
						(arc
							(start -0.1778 -0.2794)
							(mid -0.249642 -0.249642)
							(end -0.2794 -0.1778)
						)
						(arc
							(start -0.2794 0.1778)
							(mid -0.249642 0.249642)
							(end -0.1778 0.2794)
						)
						(arc
							(start 0.1778 0.2794)
							(mid 0.249642 0.249642)
							(end 0.2794 0.1778)
						)
						(arc
							(start 0.2794 -0.1778)
							(mid 0.249642 -0.249642)
							(end 0.1778 -0.2794)
						)
					)
					(width 0)
					(fill yes)
				)
			)
		)
		(pad "2" smd custom
			(at 0 0.4445 270)
			(size 0.1397 0.1397)
			(layers "F.Cu" "F.Mask" "F.Paste")
			(net "ENCLO_LED_RED_G")
			(options
				(clearance outline)
				(anchor circle)
			)
			(primitives
				(gr_poly
					(pts
						(arc
							(start -0.1778 -0.2794)
							(mid -0.249642 -0.249642)
							(end -0.2794 -0.1778)
						)
						(arc
							(start -0.2794 0.1778)
							(mid -0.249642 0.249642)
							(end -0.1778 0.2794)
						)
						(arc
							(start 0.1778 0.2794)
							(mid 0.249642 0.249642)
							(end 0.2794 0.1778)
						)
						(arc
							(start 0.2794 -0.1778)
							(mid 0.249642 -0.249642)
							(end 0.1778 -0.2794)
						)
					)
					(width 0)
					(fill yes)
				)
			)
		)
	)
	(footprint ""
		(layer "F.Cu")
		(at 229.108 -89.916 90)
		(property "Reference" "R177"
			(at 0 0 90)
			(layer "F.SilkS")
			(hide yes)
			(effects
				(font
					(size 1.27 1.27)
				)
			)
		)
		(property "Value" "4K7R2F-GP"
			(at 0.064008 -3.993896 90)
			(unlocked yes)
			(layer "F.Fab")
			(hide yes)
			(effects
				(font
					(size 1.016 1.016)
					(thickness 0.1524)
				)
			)
		)
		(property "Device Type" "R402H16"
			(at 0.064008 -5.517896 90)
			(unlocked yes)
			(layer "F.Fab")
			(hide yes)
			(effects
				(font
					(size 1.016 1.016)
					(thickness 0.1524)
				)
			)
		)
		(duplicate_pad_numbers_are_jumpers no)
		(fp_line
			(start 0.508 -0.9398)
			(end -0.508 -0.9398)
			(stroke
				(width 0.1524)
				(type default)
			)
			(layer "F.SilkS")
		)
		(fp_line
			(start -0.508 -0.9398)
			(end -0.508 0.9398)
			(stroke
				(width 0.1524)
				(type default)
			)
			(layer "F.SilkS")
		)
		(fp_rect
			(start -0.508 0.9398)
			(end 0.508 -0.9398)
			(stroke
				(width 0)
				(type default)
			)
			(fill no)
			(layer "F.CrtYd")
		)
		(fp_rect
			(start -0.508 0.9398)
			(end 0.508 -0.9398)
			(stroke
				(width 0)
				(type default)
			)
			(fill no)
			(layer "F.Fab")
		)
		(pad "1" smd custom
			(at 0 -0.4445 90)
			(size 0.1397 0.1397)
			(layers "F.Cu" "F.Mask" "F.Paste")
			(net "TEMP_3_A1")
			(options
				(clearance outline)
				(anchor circle)
			)
			(primitives
				(gr_poly
					(pts
						(arc
							(start -0.1778 -0.2794)
							(mid -0.249642 -0.249642)
							(end -0.2794 -0.1778)
						)
						(arc
							(start -0.2794 0.1778)
							(mid -0.249642 0.249642)
							(end -0.1778 0.2794)
						)
						(arc
							(start 0.1778 0.2794)
							(mid 0.249642 0.249642)
							(end 0.2794 0.1778)
						)
						(arc
							(start 0.2794 -0.1778)
							(mid 0.249642 -0.249642)
							(end 0.1778 -0.2794)
						)
					)
					(width 0)
					(fill yes)
				)
			)
		)
		(pad "2" smd custom
			(at 0 0.4445 90)
			(size 0.1397 0.1397)
			(layers "F.Cu" "F.Mask" "F.Paste")
			(net "GND")
			(options
				(clearance outline)
				(anchor circle)
			)
			(primitives
				(gr_poly
					(pts
						(arc
							(start -0.1778 -0.2794)
							(mid -0.249642 -0.249642)
							(end -0.2794 -0.1778)
						)
						(arc
							(start -0.2794 0.1778)
							(mid -0.249642 0.249642)
							(end -0.1778 0.2794)
						)
						(arc
							(start 0.1778 0.2794)
							(mid 0.249642 0.249642)
							(end 0.2794 0.1778)
						)
						(arc
							(start 0.2794 -0.1778)
							(mid 0.249642 -0.249642)
							(end 0.1778 -0.2794)
						)
					)
					(width 0)
					(fill yes)
				)
			)
		)
	)
	(footprint ""
		(layer "F.Cu")
		(at 225.679 -23.241 180)
		(property "Reference" "R3722"
			(at 0 0 180)
			(layer "F.SilkS")
			(hide yes)
			(effects
				(font
					(size 1.27 1.27)
				)
			)
		)
		(property "Value" "4K7R2F-GP"
			(at 0.064008 -3.993896 180)
			(unlocked yes)
			(layer "F.Fab")
			(hide yes)
			(effects
				(font
					(size 1.016 1.016)
					(thickness 0.1524)
				)
			)
		)
		(property "Device Type" "R402H16"
			(at 0.064008 -5.517896 180)
			(unlocked yes)
			(layer "F.Fab")
			(hide yes)
			(effects
				(font
					(size 1.016 1.016)
					(thickness 0.1524)
				)
			)
		)
		(duplicate_pad_numbers_are_jumpers no)
		(fp_line
			(start 0.508 -0.9398)
			(end -0.508 -0.9398)
			(stroke
				(width 0.1524)
				(type default)
			)
			(layer "F.SilkS")
		)
		(fp_line
			(start -0.508 -0.9398)
			(end -0.508 0.9398)
			(stroke
				(width 0.1524)
				(type default)
			)
			(layer "F.SilkS")
		)
		(fp_rect
			(start -0.508 0.9398)
			(end 0.508 -0.9398)
			(stroke
				(width 0)
				(type default)
			)
			(fill no)
			(layer "F.CrtYd")
		)
		(fp_rect
			(start -0.508 0.9398)
			(end 0.508 -0.9398)
			(stroke
				(width 0)
				(type default)
			)
			(fill no)
			(layer "F.Fab")
		)
		(pad "1" smd custom
			(at 0 -0.4445 180)
			(size 0.1397 0.1397)
			(layers "F.Cu" "F.Mask" "F.Paste")
			(net "HOST5_RST_N_LS")
			(options
				(clearance outline)
				(anchor circle)
			)
			(primitives
				(gr_poly
					(pts
						(arc
							(start -0.1778 -0.2794)
							(mid -0.249642 -0.249642)
							(end -0.2794 -0.1778)
						)
						(arc
							(start -0.2794 0.1778)
							(mid -0.249642 0.249642)
							(end -0.1778 0.2794)
						)
						(arc
							(start 0.1778 0.2794)
							(mid 0.249642 0.249642)
							(end 0.2794 0.1778)
						)
						(arc
							(start 0.2794 -0.1778)
							(mid 0.249642 -0.249642)
							(end 0.1778 -0.2794)
						)
					)
					(width 0)
					(fill yes)
				)
			)
		)
		(pad "2" smd custom
			(at 0 0.4445 180)
			(size 0.1397 0.1397)
			(layers "F.Cu" "F.Mask" "F.Paste")
			(net "GND")
			(options
				(clearance outline)
				(anchor circle)
			)
			(primitives
				(gr_poly
					(pts
						(arc
							(start -0.1778 -0.2794)
							(mid -0.249642 -0.249642)
							(end -0.2794 -0.1778)
						)
						(arc
							(start -0.2794 0.1778)
							(mid -0.249642 0.249642)
							(end -0.1778 0.2794)
						)
						(arc
							(start 0.1778 0.2794)
							(mid 0.249642 0.249642)
							(end 0.2794 0.1778)
						)
						(arc
							(start 0.2794 -0.1778)
							(mid 0.249642 -0.249642)
							(end 0.1778 -0.2794)
						)
					)
					(width 0)
					(fill yes)
				)
			)
		)
	)
	(footprint ""
		(layer "F.Cu")
		(at 145.177002 -67.058032 -90)
		(property "Reference" "PC201"
			(at 0 0 270)
			(layer "F.SilkS")
			(hide yes)
			(effects
				(font
					(size 1.27 1.27)
				)
			)
		)
		(property "Value" "SC22U25V6KX-GP-U"
			(at -2.860802 -5.279644 270)
			(unlocked yes)
			(layer "F.Fab")
			(hide yes)
			(effects
				(font
					(size 1.016 1.016)
					(thickness 0.1524)
				)
			)
		)
		(property "Device Type" "C1206-TO0D3H75"
			(at -2.860802 -6.803644 270)
			(unlocked yes)
			(layer "F.Fab")
			(hide yes)
			(effects
				(font
					(size 1.016 1.016)
					(thickness 0.1524)
				)
			)
		)
		(duplicate_pad_numbers_are_jumpers no)
		(fp_line
			(start -1.3081 2.3749)
			(end -1.3081 -2.3749)
			(stroke
				(width 0.1524)
				(type default)
			)
			(layer "F.SilkS")
		)
		(fp_line
			(start 1.3081 2.3749)
			(end -1.3081 2.3749)
			(stroke
				(width 0.1524)
				(type default)
			)
			(layer "F.SilkS")
		)
		(fp_line
			(start -1.3081 -2.3749)
			(end 1.3081 -2.3749)
			(stroke
				(width 0.1524)
				(type default)
			)
			(layer "F.SilkS")
		)
		(fp_line
			(start 1.3081 -2.3749)
			(end 1.3081 2.3749)
			(stroke
				(width 0.1524)
				(type default)
			)
			(layer "F.SilkS")
		)
		(fp_rect
			(start -0.8001 1.6002)
			(end 0.8001 -1.6002)
			(stroke
				(width 0)
				(type default)
			)
			(fill no)
			(layer "F.CrtYd")
		)
		(fp_poly
			(pts
				(xy -1.5621 2.4511) (xy -1.5621 1.6002) (xy 0.8001 1.6002) (xy 0.8001 -1.6002) (xy -0.8001 -1.6002)
				(xy -0.8001 1.5875) (xy -1.5621 1.5875) (xy -1.5621 -2.4511) (xy 1.5621 -2.4511) (xy 1.5621 2.4511)
			)
			(stroke
				(width 0)
				(type default)
			)
			(fill no)
			(layer "F.CrtYd")
		)
		(fp_rect
			(start -1.5621 2.4511)
			(end 1.5621 -2.4511)
			(stroke
				(width 0)
				(type default)
			)
			(fill no)
			(layer "F.Fab")
		)
		(pad "1" smd rect
			(at 0 -1.392936 270)
			(size 2.1082 1.4478)
			(layers "F.Cu" "F.Mask" "F.Paste")
			(net "P0V9_VIN")
		)
		(pad "2" smd rect
			(at 0 1.392936 270)
			(size 2.1082 1.4478)
			(layers "F.Cu" "F.Mask" "F.Paste")
			(net "GND")
		)
	)
)
